(kicad_pcb
	(version 20260206)
	(generator "pcbnew")
	(generator_version "10.0")
	(general
		(thickness 1.6)
		(legacy_teardrops no)
	)
	(paper "A4")
	(title_block
		(title "timecard-production-celestica-r4006 — R4006-B0001-02_R01.brd")
		(comment 1 "Time Appliance Project (Time Card) / footprints 593-597 of 1113")
	)
	(layers
		(0 "F.Cu" signal "TOP")
		(4 "In1.Cu" signal "L02_GND1")
		(6 "In2.Cu" signal "L03_SIG1")
		(8 "In3.Cu" signal "L04_GND2")
		(10 "In4.Cu" signal "L05_VCC1")
		(12 "In5.Cu" signal "L06_VCC2")
		(14 "In6.Cu" signal "L07_GND3")
		(16 "In7.Cu" signal "L08_SIG2")
		(18 "In8.Cu" signal "L09_GND4")
		(2 "B.Cu" signal "BOTTOM")
		(9 "F.Adhes" user "F.Adhesive")
		(11 "B.Adhes" user "B.Adhesive")
		(13 "F.Paste" user "Package Geometry/Pastemask Top")
		(15 "B.Paste" user "Package Geometry/Pastemask Bottom")
		(5 "F.SilkS" user "Ref Des/Silkscreen Top")
		(7 "B.SilkS" user "Ref Des/Silkscreen Bottom")
		(1 "F.Mask" user "Board Geometry/Soldermask Top")
		(3 "B.Mask" user "Board Geometry/Soldermask Bottom")
		(17 "Dwgs.User" user "User.Drawings")
		(19 "Cmts.User" user "User.Comments")
		(21 "Eco1.User" user "User.Eco1")
		(23 "Eco2.User" user "User.Eco2")
		(25 "Edge.Cuts" user "Board Geometry/Outline")
		(27 "Margin" user)
		(31 "F.CrtYd" user "Package Geometry/Place Bound Top")
		(29 "B.CrtYd" user "Package Geometry/Place Bound Bottom")
		(35 "F.Fab" user "Ref Des/Assembly Top")
		(33 "B.Fab" user "Ref Des/Assembly Bottom")
	)
	(footprint ""
		(layer "F.Cu")
		(at 108.966 -31.369 90)
		(property "Reference" "TP204"
			(at -1.17475 -0.6858 0)
			(unlocked yes)
			(layer "F.SilkS")
			(effects
				(font
					(size 0.635 0.4064)
					(thickness 0.1524)
				)
				(justify left)
			)
		)
		(property "Value" ""
			(at 0 0 90)
			(layer "F.Fab")
			(effects
				(font
					(size 1.27 1.27)
				)
			)
		)
		(property "Device Type" "TP_PIONT-TP010CT020B030_PTH-TPA"
			(at -1.341882 0.996696 90)
			(unlocked yes)
			(layer "F.Fab")
			(hide yes)
			(effects
				(font
					(size 0.7874 0.5842)
					(thickness 0.1524)
				)
				(justify left)
			)
		)
		(duplicate_pad_numbers_are_jumpers no)
		(fp_poly
			(pts
				(arc
					(start 0 0.889)
					(mid 0 -0.889)
					(end 0 0.889)
				)
			)
			(stroke
				(width 0)
				(type default)
			)
			(fill no)
			(layer "B.CrtYd")
		)
		(fp_poly
			(pts
				(arc
					(start 0 0.889)
					(mid 0 -0.889)
					(end 0 0.889)
				)
			)
			(stroke
				(width 0)
				(type default)
			)
			(fill no)
			(layer "F.CrtYd")
		)
		(pad "1" thru_hole circle
			(at 0 0 90)
			(size 0.508 0.508)
			(drill 0.254)
			(layers "*.Cu" "*.Mask")
			(remove_unused_layers no)
			(net "IO_L24N_35")
			(clearance 0.1016)
			(padstack
				(mode front_inner_back)
				(layer "Inner"
					(shape circle)
					(size 0.508 0.508)
					(clearance 0.1016)
				)
				(layer "B.Cu"
					(shape circle)
					(size 0.762 0.762)
					(clearance -0.0254)
				)
			)
		)
	)
	(footprint ""
		(layer "F.Cu")
		(at 103.9622 -64.2874 -90)
		(property "Reference" "R308"
			(at 2.6924 -0.85217 90)
			(unlocked yes)
			(layer "F.SilkS")
			(effects
				(font
					(size 0.7874 0.5842)
					(thickness 0.1524)
				)
			)
		)
		(property "Value" "VAL*"
			(at 0.02032 2.13233 270)
			(unlocked yes)
			(layer "F.Fab")
			(hide yes)
			(effects
				(font
					(size 0.7874 0.5842)
					(thickness 0.1524)
				)
			)
		)
		(property "Tolerance" "TOL*"
			(at 0.044704 3.05435 270)
			(unlocked yes)
			(layer "Cmts.User")
			(hide yes)
			(effects
				(font
					(size 0.7874 0.5842)
					(thickness 0.1524)
				)
			)
		)
		(property "User Part Number" "PARTNUM*"
			(at 0.02032 4.024884 270)
			(unlocked yes)
			(layer "Cmts.User")
			(hide yes)
			(effects
				(font
					(size 0.7874 0.5842)
					(thickness 0.1524)
				)
			)
		)
		(property "Device Type" "RESISTOR-G155-11002-01,10KOHM,A"
			(at 0.008382 1.210564 270)
			(unlocked yes)
			(layer "F.Fab")
			(hide yes)
			(effects
				(font
					(size 0.7874 0.5842)
					(thickness 0.1524)
				)
			)
		)
		(duplicate_pad_numbers_are_jumpers no)
		(fp_line
			(start -1.143 0.5588)
			(end 1.143 0.5588)
			(stroke
				(width 0.1)
				(type default)
			)
			(layer "F.SilkS")
		)
		(fp_line
			(start 1.143 0.5588)
			(end 1.143 -0.5588)
			(stroke
				(width 0.1)
				(type default)
			)
			(layer "F.SilkS")
		)
		(fp_line
			(start -1.143 -0.5588)
			(end -1.143 0.5588)
			(stroke
				(width 0.1)
				(type default)
			)
			(layer "F.SilkS")
		)
		(fp_line
			(start 1.143 -0.5588)
			(end -1.143 -0.5588)
			(stroke
				(width 0.1)
				(type default)
			)
			(layer "F.SilkS")
		)
		(fp_poly
			(pts
				(xy -1.143 0.5588) (xy 1.143 0.5588) (xy 1.143 -0.5588) (xy -1.143 -0.5588)
			)
			(stroke
				(width 0)
				(type default)
			)
			(fill no)
			(layer "F.CrtYd")
		)
		(fp_line
			(start -0.508 0.3048)
			(end 0.508 0.3048)
			(stroke
				(width 0.1)
				(type default)
			)
			(layer "F.Fab")
		)
		(fp_line
			(start 0.508 0.3048)
			(end 0.508 -0.3048)
			(stroke
				(width 0.1)
				(type default)
			)
			(layer "F.Fab")
		)
		(fp_line
			(start -0.508 -0.3048)
			(end -0.508 0.3048)
			(stroke
				(width 0.1)
				(type default)
			)
			(layer "F.Fab")
		)
		(fp_line
			(start 0.508 -0.3048)
			(end -0.508 -0.3048)
			(stroke
				(width 0.1)
				(type default)
			)
			(layer "F.Fab")
		)
		(pad "1" smd rect
			(at -0.5334 0 270)
			(size 0.7112 0.6096)
			(layers "F.Cu" "F.Mask" "F.Paste")
			(net "XP3R3V_FPGA")
		)
		(pad "2" smd rect
			(at 0.5334 0 270)
			(size 0.7112 0.6096)
			(layers "F.Cu" "F.Mask" "F.Paste")
			(net "FPGA_IO_5")
		)
		(zone
			(layer "F.Cu")
			(hatch none 0.5)
			(connect_pads
				(clearance 0)
			)
			(min_thickness 0.25)
			(keepout
				(tracks not_allowed)
				(vias allowed)
				(pads allowed)
				(copperpour not_allowed)
				(footprints allowed)
			)
			(placement
				(enabled no)
				(sheetname "")
			)
			(fill
				(thermal_gap 0.5)
				(thermal_bridge_width 0.5)
				(island_removal_mode 0)
			)
			(polygon
				(pts
					(xy 103.6574 -64.3636) (xy 103.6574 -64.2112) (xy 104.267 -64.2112) (xy 104.267 -64.3636)
				)
			)
		)
		(zone
			(layer "F.Cu")
			(hatch none 0.5)
			(connect_pads
				(clearance 0)
			)
			(min_thickness 0.25)
			(keepout
				(tracks allowed)
				(vias not_allowed)
				(pads allowed)
				(copperpour not_allowed)
				(footprints allowed)
			)
			(placement
				(enabled no)
				(sheetname "")
			)
			(fill
				(thermal_gap 0.5)
				(thermal_bridge_width 0.5)
				(island_removal_mode 0)
			)
			(polygon
				(pts
					(xy 103.6574 -64.3636) (xy 103.6574 -64.2112) (xy 104.267 -64.2112) (xy 104.267 -64.3636)
				)
			)
		)
	)
	(footprint ""
		(layer "F.Cu")
		(at 77.851 -43.053)
		(property "Reference" "TP51"
			(at -1.48463 2.8702 90)
			(unlocked yes)
			(layer "F.SilkS")
			(effects
				(font
					(size 0.7874 0.5842)
					(thickness 0.1524)
				)
				(justify left)
			)
		)
		(property "Value" ""
			(at 0 0 0)
			(layer "F.Fab")
			(effects
				(font
					(size 1.27 1.27)
				)
			)
		)
		(property "Device Type" "TP_PIONT-TP010CT020B030_PTH-TPA"
			(at -1.341882 0.996696 0)
			(unlocked yes)
			(layer "F.Fab")
			(hide yes)
			(effects
				(font
					(size 0.7874 0.5842)
					(thickness 0.000001)
				)
				(justify left)
			)
		)
		(duplicate_pad_numbers_are_jumpers no)
		(fp_poly
			(pts
				(arc
					(start 0.889 0)
					(mid -0.889 0)
					(end 0.889 0)
				)
			)
			(stroke
				(width 0)
				(type default)
			)
			(fill no)
			(layer "B.CrtYd")
		)
		(fp_poly
			(pts
				(arc
					(start 0.889 0)
					(mid -0.889 0)
					(end 0.889 0)
				)
			)
			(stroke
				(width 0)
				(type default)
			)
			(fill no)
			(layer "F.CrtYd")
		)
		(pad "1" thru_hole circle
			(at 0 0)
			(size 0.508 0.508)
			(drill 0.254)
			(layers "*.Cu" "*.Mask")
			(remove_unused_layers no)
			(net "MAC_ALARM")
			(clearance 0.1016)
			(padstack
				(mode front_inner_back)
				(layer "Inner"
					(shape circle)
					(size 0.508 0.508)
					(clearance 0.1016)
				)
				(layer "B.Cu"
					(shape circle)
					(size 0.762 0.762)
					(clearance -0.0254)
				)
			)
		)
	)
	(footprint ""
		(layer "F.Cu")
		(at 13.068808 -57.2516 90)
		(property "Reference" "R381"
			(at -0.3556 -2.361438 90)
			(unlocked yes)
			(layer "F.SilkS")
			(effects
				(font
					(size 0.7874 0.5842)
					(thickness 0.1524)
				)
			)
		)
		(property "Value" "VAL*"
			(at 0.02032 2.13233 90)
			(unlocked yes)
			(layer "F.Fab")
			(hide yes)
			(effects
				(font
					(size 0.7874 0.5842)
					(thickness 0.1524)
				)
			)
		)
		(property "Device Type" "RESISTOR-G155-14701-01,4.7KOHMA"
			(at 0.008382 1.210564 90)
			(unlocked yes)
			(layer "F.Fab")
			(hide yes)
			(effects
				(font
					(size 0.7874 0.5842)
					(thickness 0.1524)
				)
			)
		)
		(property "User Part Number" "PARTNUM*"
			(at 0.02032 4.024884 90)
			(unlocked yes)
			(layer "Cmts.User")
			(hide yes)
			(effects
				(font
					(size 0.7874 0.5842)
					(thickness 0.1524)
				)
			)
		)
		(property "Tolerance" "TOL*"
			(at 0.044704 3.05435 90)
			(unlocked yes)
			(layer "Cmts.User")
			(hide yes)
			(effects
				(font
					(size 0.7874 0.5842)
					(thickness 0.1524)
				)
			)
		)
		(duplicate_pad_numbers_are_jumpers no)
		(fp_line
			(start 1.143 -0.5588)
			(end -1.143 -0.5588)
			(stroke
				(width 0.1)
				(type default)
			)
			(layer "F.SilkS")
		)
		(fp_line
			(start -1.143 -0.5588)
			(end -1.143 0.5588)
			(stroke
				(width 0.1)
				(type default)
			)
			(layer "F.SilkS")
		)
		(fp_line
			(start 1.143 0.5588)
			(end 1.143 -0.5588)
			(stroke
				(width 0.1)
				(type default)
			)
			(layer "F.SilkS")
		)
		(fp_line
			(start -1.143 0.5588)
			(end 1.143 0.5588)
			(stroke
				(width 0.1)
				(type default)
			)
			(layer "F.SilkS")
		)
		(fp_rect
			(start 1.143 0.5588)
			(end -1.143 -0.5588)
			(stroke
				(width 0)
				(type default)
			)
			(fill no)
			(layer "F.CrtYd")
		)
		(fp_line
			(start 0.508 -0.3048)
			(end -0.508 -0.3048)
			(stroke
				(width 0.1)
				(type default)
			)
			(layer "F.Fab")
		)
		(fp_line
			(start -0.508 -0.3048)
			(end -0.508 0.3048)
			(stroke
				(width 0.1)
				(type default)
			)
			(layer "F.Fab")
		)
		(fp_line
			(start 0.508 0.3048)
			(end 0.508 -0.3048)
			(stroke
				(width 0.1)
				(type default)
			)
			(layer "F.Fab")
		)
		(fp_line
			(start -0.508 0.3048)
			(end 0.508 0.3048)
			(stroke
				(width 0.1)
				(type default)
			)
			(layer "F.Fab")
		)
		(pad "1" smd rect
			(at -0.5334 0 90)
			(size 0.7112 0.6096)
			(layers "F.Cu" "F.Mask" "F.Paste")
			(net "XP3R3V_FPGA")
		)
		(pad "2" smd rect
			(at 0.5334 0 90)
			(size 0.7112 0.6096)
			(layers "F.Cu" "F.Mask" "F.Paste")
			(net "SMA1_SIG_IN_BF_EN_N")
		)
		(zone
			(layer "F.Cu")
			(hatch none 0.5)
			(connect_pads
				(clearance 0)
			)
			(min_thickness 0.25)
			(keepout
				(tracks not_allowed)
				(vias allowed)
				(pads allowed)
				(copperpour not_allowed)
				(footprints allowed)
			)
			(placement
				(enabled no)
				(sheetname "")
			)
			(fill
				(thermal_gap 0.5)
				(thermal_bridge_width 0.5)
				(island_removal_mode 0)
			)
			(polygon
				(pts
					(xy 13.373608 -57.3278) (xy 12.764008 -57.3278) (xy 12.764008 -57.1754) (xy 13.373608 -57.1754)
				)
			)
		)
		(zone
			(layer "F.Cu")
			(hatch none 0.5)
			(connect_pads
				(clearance 0)
			)
			(min_thickness 0.25)
			(keepout
				(tracks allowed)
				(vias not_allowed)
				(pads allowed)
				(copperpour not_allowed)
				(footprints allowed)
			)
			(placement
				(enabled no)
				(sheetname "")
			)
			(fill
				(thermal_gap 0.5)
				(thermal_bridge_width 0.5)
				(island_removal_mode 0)
			)
			(polygon
				(pts
					(xy 13.373608 -57.3278) (xy 12.764008 -57.3278) (xy 12.764008 -57.1754) (xy 13.373608 -57.1754)
				)
			)
		)
	)
	(footprint ""
		(layer "F.Cu")
		(at 31.877 -98.679 180)
		(property "Reference" "Y2"
			(at 1.143 3.13563 0)
			(unlocked yes)
			(layer "F.SilkS")
			(effects
				(font
					(size 0.7874 0.5842)
					(thickness 0.1524)
				)
			)
		)
		(property "Value" ""
			(at 0 0 180)
			(layer "F.Fab")
			(effects
				(font
					(size 1.27 1.27)
				)
			)
		)
		(property "User Part Number" "PARTNUM*"
			(at 0.009906 4.56819 180)
			(unlocked yes)
			(layer "Cmts.User")
			(hide yes)
			(effects
				(font
					(size 0.7874 0.5842)
					(thickness 0.1524)
				)
			)
		)
		(property "Device Type" "XTAL_4-G131-10038-02"
			(at 0.009906 3.37439 180)
			(unlocked yes)
			(layer "F.Fab")
			(hide yes)
			(effects
				(font
					(size 0.7874 0.5842)
					(thickness 0.1524)
				)
			)
		)
		(duplicate_pad_numbers_are_jumpers no)
		(fp_line
			(start 2.052574 1.700784)
			(end -2.052574 1.700784)
			(stroke
				(width 0.1)
				(type default)
			)
			(layer "F.SilkS")
		)
		(fp_line
			(start 2.052574 -1.700784)
			(end 2.052574 1.700784)
			(stroke
				(width 0.1)
				(type default)
			)
			(layer "F.SilkS")
		)
		(fp_line
			(start -2.052574 1.700784)
			(end -2.052574 -1.700784)
			(stroke
				(width 0.1)
				(type default)
			)
			(layer "F.SilkS")
		)
		(fp_line
			(start -2.052574 -1.700784)
			(end 2.052574 -1.700784)
			(stroke
				(width 0.1)
				(type default)
			)
			(layer "F.SilkS")
		)
		(fp_poly
			(pts
				(arc
					(start -1.799336 2.413)
					(mid -1.037336 2.413)
					(end -1.799336 2.413)
				)
			)
			(stroke
				(width 0)
				(type default)
			)
			(fill yes)
			(layer "F.SilkS")
		)
		(fp_rect
			(start 2.306574 1.954784)
			(end -2.306574 -1.954784)
			(stroke
				(width 0)
				(type default)
			)
			(fill no)
			(layer "F.CrtYd")
		)
		(fp_line
			(start 1.649984 1.299972)
			(end -1.649984 1.299972)
			(stroke
				(width 0.1)
				(type default)
			)
			(layer "F.Fab")
		)
		(fp_line
			(start 1.649984 -1.299972)
			(end 1.649984 1.299972)
			(stroke
				(width 0.1)
				(type default)
			)
			(layer "F.Fab")
		)
		(fp_line
			(start -1.649984 1.299972)
			(end -1.649984 -1.299972)
			(stroke
				(width 0.1)
				(type default)
			)
			(layer "F.Fab")
		)
		(fp_line
			(start -1.649984 -1.299972)
			(end 1.649984 -1.299972)
			(stroke
				(width 0.1)
				(type default)
			)
			(layer "F.Fab")
		)
		(fp_poly
			(pts
				(arc
					(start -1.799336 2.032)
					(mid -1.037336 2.032)
					(end -1.799336 2.032)
				)
			)
			(stroke
				(width 0)
				(type default)
			)
			(fill yes)
			(layer "F.Fab")
		)
		(fp_text user "2"
			(at 2.667 2.62763 0)
			(unlocked yes)
			(layer "F.SilkS")
			(effects
				(font
					(size 0.7874 0.5842)
					(thickness 0.1524)
				)
			)
		)
		(fp_text user "3"
			(at 2.54 -2.07137 0)
			(unlocked yes)
			(layer "F.SilkS")
			(effects
				(font
					(size 0.7874 0.5842)
					(thickness 0.1524)
				)
			)
		)
		(fp_text user "4"
			(at -2.667 -2.07137 0)
			(unlocked yes)
			(layer "F.SilkS")
			(effects
				(font
					(size 0.7874 0.5842)
					(thickness 0.1524)
				)
			)
		)
		(fp_text user "3"
			(at 2.286 -1.43637 0)
			(unlocked yes)
			(layer "F.Fab")
			(effects
				(font
					(size 0.7874 0.5842)
					(thickness 0.1524)
				)
			)
		)
		(fp_text user "2"
			(at 2.159 1.99263 0)
			(unlocked yes)
			(layer "F.Fab")
			(effects
				(font
					(size 0.7874 0.5842)
					(thickness 0.1524)
				)
			)
		)
		(fp_text user "4"
			(at -2.413 -1.30937 0)
			(unlocked yes)
			(layer "F.Fab")
			(effects
				(font
					(size 0.7874 0.5842)
					(thickness 0.1524)
				)
			)
		)
		(pad "1" smd rect
			(at -1.100074 0.849884 180)
			(size 1.397 1.1938)
			(layers "F.Cu" "F.Mask" "F.Paste")
			(net "UNNAMED_524_CAPACITOR_I7_2")
		)
		(pad "2" smd rect
			(at 1.100074 0.849884 180)
			(size 1.397 1.1938)
			(layers "F.Cu" "F.Mask" "F.Paste")
			(net "SG")
		)
		(pad "3" smd rect
			(at 1.100074 -0.849884 180)
			(size 1.397 1.1938)
			(layers "F.Cu" "F.Mask" "F.Paste")
			(net "UNNAMED_524_CAPACITOR_I10_2")
		)
		(pad "4" smd rect
			(at -1.100074 -0.849884 180)
			(size 1.397 1.1938)
			(layers "F.Cu" "F.Mask" "F.Paste")
			(net "SG")
		)
		(zone
			(layer "F.Cu")
			(hatch none 0.5)
			(connect_pads
				(clearance 0)
			)
			(min_thickness 0.25)
			(keepout
				(tracks allowed)
				(vias not_allowed)
				(pads allowed)
				(copperpour not_allowed)
				(footprints allowed)
			)
			(placement
				(enabled no)
				(sheetname "")
			)
			(fill
				(thermal_gap 0.5)
				(thermal_bridge_width 0.5)
				(island_removal_mode 0)
			)
			(polygon
				(pts
					(xy 32.278574 -99.978972) (xy 32.278574 -98.931984) (xy 33.526984 -98.931984) (xy 33.526984 -98.426016)
					(xy 32.278574 -98.426016) (xy 32.278574 -97.379028) (xy 31.475426 -97.379028) (xy 31.475426 -98.426016)
					(xy 30.227016 -98.426016) (xy 30.227016 -98.931984) (xy 31.475426 -98.931984) (xy 31.475426 -99.978972)
				)
			)
		)
	)
)
